# T6G (Grand Teton) — schematic netlist excerpt (pin names and nets, part order shuffled) for the footprints in the layout excerpt that follows; sources: Cadence DE-HDL packaged netlist, KiCad conversion of 04192023_DAF0TMB3IC0_F0TG_MB_C_brd_V02_OCP.brd

R1275  Q_RES  0 5% CHIP  pkg 0402LF  page 357 : A = SMB_INA230_8_3V3AUX_SDA_R ; B = SMB_INA230_8_3V3AUX_SDA_R1
R6307  Q_RES  4.7K 1% EMPTY  pkg 0402LF  page 179 : A = USB_HUB2_TI_HS_SUSPEND ; B = GND

(kicad_pcb
	(version 20260206)
	(generator "pcbnew")
	(generator_version "10.0")
	(general
		(thickness 1.6)
		(legacy_teardrops no)
	)
	(paper "A4")
	(title_block
		(title "04192023_DAF0TMB3IC0_F0TG_MB_C_brd_V02_OCP.brd")
		(comment 1 "Grand Teton / footprints 3308-3309 of 8354")
	)
	(layers
		(0 "F.Cu" signal "TOP")
		(4 "In1.Cu" signal "GND")
		(6 "In2.Cu" signal "IN1")
		(8 "In3.Cu" signal "GND1")
		(10 "In4.Cu" signal "IN2")
		(12 "In5.Cu" signal "GND2")
		(14 "In6.Cu" signal "IN3")
		(16 "In7.Cu" signal "GND3")
		(18 "In8.Cu" signal "VCC")
		(20 "In9.Cu" signal "VCC1")
		(22 "In10.Cu" signal "GND4")
		(24 "In11.Cu" signal "IN4")
		(26 "In12.Cu" signal "GND5")
		(28 "In13.Cu" signal "IN5")
		(30 "In14.Cu" signal "GND6")
		(32 "In15.Cu" signal "IN6")
		(34 "In16.Cu" signal "GND7")
		(2 "B.Cu" signal "BOTTOM")
		(9 "F.Adhes" user "F.Adhesive")
		(11 "B.Adhes" user "B.Adhesive")
		(13 "F.Paste" user "Package Geometry/Pastemask Top")
		(15 "B.Paste" user "Package Geometry/Pastemask Bottom")
		(5 "F.SilkS" user "Ref Des/Silkscreen Top")
		(7 "B.SilkS" user "Ref Des/Silkscreen Bottom")
		(1 "F.Mask" user "Board Geometry/Soldermask Top")
		(3 "B.Mask" user "Board Geometry/Soldermask Bottom")
		(17 "Dwgs.User" user "User.Drawings")
		(19 "Cmts.User" user "User.Comments")
		(21 "Eco1.User" user "User.Eco1")
		(23 "Eco2.User" user "User.Eco2")
		(25 "Edge.Cuts" user "Board Geometry/Outline")
		(27 "Margin" user)
		(31 "F.CrtYd" user "Package Geometry/Place Bound Top")
		(29 "B.CrtYd" user "Package Geometry/Place Bound Bottom")
		(35 "F.Fab" user "Ref Des/Assembly Top")
		(33 "B.Fab" user "Ref Des/Assembly Bottom")
	)
	(footprint ""
		(layer "F.Cu")
		(at 109.549946 -52.86248 -90)
		(property "Reference" "R6307"
			(at 0 0 270)
			(layer "F.SilkS")
			(hide yes)
			(effects
				(font
					(size 1.27 1.27)
				)
			)
		)
		(property "Value" ""
			(at 0 0 270)
			(layer "F.Fab")
			(effects
				(font
					(size 1.27 1.27)
				)
			)
		)
		(duplicate_pad_numbers_are_jumpers no)
		(fp_line
			(start -0.7874 0.4064)
			(end -0.7874 -0.4064)
			(stroke
				(width 0.1524)
				(type default)
			)
			(layer "F.SilkS")
		)
		(fp_line
			(start 0.7874 0.4064)
			(end -0.7874 0.4064)
			(stroke
				(width 0.1524)
				(type default)
			)
			(layer "F.SilkS")
		)
		(fp_line
			(start -0.7874 -0.4064)
			(end 0.7874 -0.4064)
			(stroke
				(width 0.1524)
				(type default)
			)
			(layer "F.SilkS")
		)
		(fp_line
			(start 0.7874 -0.4064)
			(end 0.7874 0.4064)
			(stroke
				(width 0.1524)
				(type default)
			)
			(layer "F.SilkS")
		)
		(fp_line
			(start -0.67945 0.3048)
			(end -0.67945 -0.305054)
			(stroke
				(width 0.1)
				(type default)
			)
			(layer "F.Fab")
		)
		(fp_line
			(start -0.12065 0.3048)
			(end -0.67945 0.3048)
			(stroke
				(width 0.1)
				(type default)
			)
			(layer "F.Fab")
		)
		(fp_line
			(start 0.120396 0.3048)
			(end 0.120396 0.2794)
			(stroke
				(width 0.1)
				(type default)
			)
			(layer "F.Fab")
		)
		(fp_line
			(start 0.67945 0.3048)
			(end 0.120396 0.3048)
			(stroke
				(width 0.1)
				(type default)
			)
			(layer "F.Fab")
		)
		(fp_line
			(start -0.12065 0.2794)
			(end -0.12065 0.3048)
			(stroke
				(width 0.1)
				(type default)
			)
			(layer "F.Fab")
		)
		(fp_line
			(start 0.120396 0.2794)
			(end -0.12065 0.2794)
			(stroke
				(width 0.1)
				(type default)
			)
			(layer "F.Fab")
		)
		(fp_line
			(start -0.12065 -0.2794)
			(end 0.12065 -0.2794)
			(stroke
				(width 0.1)
				(type default)
			)
			(layer "F.Fab")
		)
		(fp_line
			(start 0.12065 -0.2794)
			(end 0.12065 -0.3048)
			(stroke
				(width 0.1)
				(type default)
			)
			(layer "F.Fab")
		)
		(fp_line
			(start 0.12065 -0.3048)
			(end 0.67945 -0.3048)
			(stroke
				(width 0.1)
				(type default)
			)
			(layer "F.Fab")
		)
		(fp_line
			(start 0.67945 -0.3048)
			(end 0.67945 0.3048)
			(stroke
				(width 0.1)
				(type default)
			)
			(layer "F.Fab")
		)
		(fp_line
			(start -0.67945 -0.305054)
			(end -0.12065 -0.305054)
			(stroke
				(width 0.1)
				(type default)
			)
			(layer "F.Fab")
		)
		(fp_line
			(start -0.12065 -0.305054)
			(end -0.12065 -0.2794)
			(stroke
				(width 0.1)
				(type default)
			)
			(layer "F.Fab")
		)
		(pad "1" smd circle
			(at -0.40005 0 270)
			(size 0 0)
			(layers "F.Cu" "F.Mask" "F.Paste")
			(net "USB_HUB2_TI_HS_SUSPEND")
		)
		(pad "2" smd circle
			(at 0.40005 0 270)
			(size 0 0)
			(layers "F.Cu" "F.Mask" "F.Paste")
			(net "GND")
		)
	)
	(footprint ""
		(layer "F.Cu")
		(at 323.100446 -99.284536)
		(property "Reference" "R1275"
			(at 0 0 0)
			(layer "F.SilkS")
			(hide yes)
			(effects
				(font
					(size 1.27 1.27)
				)
			)
		)
		(property "Value" ""
			(at 0 0 0)
			(layer "F.Fab")
			(effects
				(font
					(size 1.27 1.27)
				)
			)
		)
		(duplicate_pad_numbers_are_jumpers no)
		(fp_line
			(start -0.7874 -0.4064)
			(end 0.7874 -0.4064)
			(stroke
				(width 0.1524)
				(type default)
			)
			(layer "F.SilkS")
		)
		(fp_line
			(start -0.7874 0.4064)
			(end -0.7874 -0.4064)
			(stroke
				(width 0.1524)
				(type default)
			)
			(layer "F.SilkS")
		)
		(fp_line
			(start 0.7874 -0.4064)
			(end 0.7874 0.4064)
			(stroke
				(width 0.1524)
				(type default)
			)
			(layer "F.SilkS")
		)
		(fp_line
			(start 0.7874 0.4064)
			(end -0.7874 0.4064)
			(stroke
				(width 0.1524)
				(type default)
			)
			(layer "F.SilkS")
		)
		(fp_line
			(start -0.67945 -0.305054)
			(end -0.12065 -0.305054)
			(stroke
				(width 0.1)
				(type default)
			)
			(layer "F.Fab")
		)
		(fp_line
			(start -0.67945 0.3048)
			(end -0.67945 -0.305054)
			(stroke
				(width 0.1)
				(type default)
			)
			(layer "F.Fab")
		)
		(fp_line
			(start -0.12065 -0.305054)
			(end -0.12065 -0.2794)
			(stroke
				(width 0.1)
				(type default)
			)
			(layer "F.Fab")
		)
		(fp_line
			(start -0.12065 -0.2794)
			(end 0.12065 -0.2794)
			(stroke
				(width 0.1)
				(type default)
			)
			(layer "F.Fab")
		)
		(fp_line
			(start -0.12065 0.2794)
			(end -0.12065 0.3048)
			(stroke
				(width 0.1)
				(type default)
			)
			(layer "F.Fab")
		)
		(fp_line
			(start -0.12065 0.3048)
			(end -0.67945 0.3048)
			(stroke
				(width 0.1)
				(type default)
			)
			(layer "F.Fab")
		)
		(fp_line
			(start 0.120396 0.2794)
			(end -0.12065 0.2794)
			(stroke
				(width 0.1)
				(type default)
			)
			(layer "F.Fab")
		)
		(fp_line
			(start 0.120396 0.3048)
			(end 0.120396 0.2794)
			(stroke
				(width 0.1)
				(type default)
			)
			(layer "F.Fab")
		)
		(fp_line
			(start 0.12065 -0.3048)
			(end 0.67945 -0.3048)
			(stroke
				(width 0.1)
				(type default)
			)
			(layer "F.Fab")
		)
		(fp_line
			(start 0.12065 -0.2794)
			(end 0.12065 -0.3048)
			(stroke
				(width 0.1)
				(type default)
			)
			(layer "F.Fab")
		)
		(fp_line
			(start 0.67945 -0.3048)
			(end 0.67945 0.3048)
			(stroke
				(width 0.1)
				(type default)
			)
			(layer "F.Fab")
		)
		(fp_line
			(start 0.67945 0.3048)
			(end 0.120396 0.3048)
			(stroke
				(width 0.1)
				(type default)
			)
			(layer "F.Fab")
		)
		(pad "1" smd circle
			(at -0.40005 0)
			(size 0 0)
			(layers "F.Cu" "F.Mask" "F.Paste")
			(net "SMB_INA230_8_3V3AUX_SDA_R")
		)
		(pad "2" smd circle
			(at 0.40005 0)
			(size 0 0)
			(layers "F.Cu" "F.Mask" "F.Paste")
			(net "SMB_INA230_8_3V3AUX_SDA_R1")
		)
	)
)
